(kicad_pcb
	(version 20260206)
	(generator "pcbnew")
	(generator_version "10.0")
	(general
		(thickness 1.6)
		(legacy_teardrops no)
	)
	(paper "A4")
	(title_block
		(title "v1-chassis-manager — T6M_CM_d_v01_1031_1645.brd")
		(comment 1 "Open CloudServer (Microsoft) / footprints 1069-1077 of 2512")
	)
	(layers
		(0 "F.Cu" signal "TOP")
		(4 "In1.Cu" signal "GND1")
		(6 "In2.Cu" signal "IN1")
		(8 "In3.Cu" signal "VCC1")
		(10 "In4.Cu" signal "VCC2")
		(12 "In5.Cu" signal "GND2")
		(14 "In6.Cu" signal "IN2")
		(16 "In7.Cu" signal "IN3")
		(18 "In8.Cu" signal "GND3")
		(2 "B.Cu" signal "BOTTOM")
		(9 "F.Adhes" user "F.Adhesive")
		(11 "B.Adhes" user "B.Adhesive")
		(13 "F.Paste" user "Package Geometry/Pastemask Top")
		(15 "B.Paste" user "Package Geometry/Pastemask Bottom")
		(5 "F.SilkS" user "Ref Des/Silkscreen Top")
		(7 "B.SilkS" user "Ref Des/Silkscreen Bottom")
		(1 "F.Mask" user "Board Geometry/Soldermask Top")
		(3 "B.Mask" user "Board Geometry/Soldermask Bottom")
		(17 "Dwgs.User" user "User.Drawings")
		(19 "Cmts.User" user "User.Comments")
		(21 "Eco1.User" user "User.Eco1")
		(23 "Eco2.User" user "User.Eco2")
		(25 "Edge.Cuts" user "Board Geometry/Outline")
		(27 "Margin" user)
		(31 "F.CrtYd" user "Package Geometry/Place Bound Top")
		(29 "B.CrtYd" user "Package Geometry/Place Bound Bottom")
		(35 "F.Fab" user "Ref Des/Assembly Top")
		(33 "B.Fab" user "Ref Des/Assembly Bottom")
	)
	(footprint ""
		(layer "F.Cu")
		(at 65.672462 -110.333028 90)
		(property "Reference" "Q38"
			(at 0.121666 -2.182876 90)
			(unlocked yes)
			(layer "F.SilkS")
			(effects
				(font
					(size 0.7874 0.5842)
					(thickness 0.1524)
				)
			)
		)
		(property "Value" ""
			(at 0 0 90)
			(layer "F.Fab")
			(effects
				(font
					(size 1.27 1.27)
				)
			)
		)
		(duplicate_pad_numbers_are_jumpers no)
		(fp_line
			(start 1.603248 -1.500124)
			(end 1.603248 1.500124)
			(stroke
				(width 0.1524)
				(type default)
			)
			(layer "F.SilkS")
		)
		(fp_line
			(start -1.603248 -1.500124)
			(end 1.603248 -1.500124)
			(stroke
				(width 0.1524)
				(type default)
			)
			(layer "F.SilkS")
		)
		(fp_line
			(start 1.603248 1.500124)
			(end -1.603248 1.500124)
			(stroke
				(width 0.1524)
				(type default)
			)
			(layer "F.SilkS")
		)
		(fp_line
			(start -1.603248 1.500124)
			(end -1.603248 -1.500124)
			(stroke
				(width 0.1524)
				(type default)
			)
			(layer "F.SilkS")
		)
		(fp_poly
			(pts
				(xy -0.700024 -1.500124) (xy -0.700024 -1.40716) (xy -1.507998 -1.40716) (xy -1.507998 -0.49276)
				(xy -0.700024 -0.49276) (xy -0.700024 0.47244) (xy -1.507998 0.47244) (xy -1.507998 1.41224) (xy -0.700024 1.41224)
				(xy -0.700024 1.500124) (xy 0.700024 1.500124) (xy 0.700024 0.47244) (xy 1.514602 0.47244) (xy 1.514602 -0.46736)
				(xy 0.700024 -0.46736) (xy 0.700024 -1.500124)
			)
			(stroke
				(width 0)
				(type default)
			)
			(fill no)
			(layer "F.CrtYd")
		)
		(fp_line
			(start 0.700024 -1.500124)
			(end 0.700024 1.500124)
			(stroke
				(width 0.1)
				(type default)
			)
			(layer "F.Fab")
		)
		(fp_line
			(start -0.700024 -1.500124)
			(end 0.700024 -1.500124)
			(stroke
				(width 0.1)
				(type default)
			)
			(layer "F.Fab")
		)
		(fp_line
			(start 0.700024 1.500124)
			(end -0.700024 1.500124)
			(stroke
				(width 0.1)
				(type default)
			)
			(layer "F.Fab")
		)
		(fp_line
			(start -0.700024 1.500124)
			(end -0.700024 -1.500124)
			(stroke
				(width 0.1)
				(type default)
			)
			(layer "F.Fab")
		)
		(fp_text user "G"
			(at -2.637536 -2.028444 90)
			(unlocked yes)
			(layer "F.SilkS")
			(effects
				(font
					(size 0.635 0.4064)
					(thickness 0.1524)
				)
			)
		)
		(fp_text user "D"
			(at 2.188464 1.273556 90)
			(unlocked yes)
			(layer "F.SilkS")
			(effects
				(font
					(size 0.635 0.4064)
					(thickness 0.1524)
				)
			)
		)
		(fp_text user "S"
			(at -2.256536 2.416556 90)
			(unlocked yes)
			(layer "F.SilkS")
			(effects
				(font
					(size 0.635 0.4064)
					(thickness 0.1524)
				)
			)
		)
		(fp_text user "G"
			(at -1.051306 -2.032 0)
			(unlocked yes)
			(layer "F.Fab")
			(effects
				(font
					(size 0.7874 0.5842)
					(thickness 0.000001)
				)
			)
		)
		(fp_text user "D"
			(at 2.098294 0.1016 0)
			(unlocked yes)
			(layer "F.Fab")
			(effects
				(font
					(size 0.7874 0.5842)
					(thickness 0.000001)
				)
			)
		)
		(fp_text user "S"
			(at -1.025906 2.0066 0)
			(unlocked yes)
			(layer "F.Fab")
			(effects
				(font
					(size 0.7874 0.5842)
					(thickness 0.000001)
				)
			)
		)
		(pad "D" smd rect
			(at 0.999998 0)
			(size 0.8128 0.9144)
			(layers "F.Cu" "F.Mask" "F.Paste")
			(net "FM_CPLD_NODE1_P1V8_EN_LV")
		)
		(pad "G" smd rect
			(at -0.999998 -0.94996)
			(size 0.8128 0.9144)
			(layers "F.Cu" "F.Mask" "F.Paste")
			(net "FM_CPLD_NODE1_P1V8_EN_G")
		)
		(pad "S" smd rect
			(at -0.999998 0.94996)
			(size 0.8128 0.9144)
			(layers "F.Cu" "F.Mask" "F.Paste")
			(net "FM_CPLD_NODE1_P1V8_EN")
		)
	)
	(footprint ""
		(layer "F.Cu")
		(at 34.990786 -173.4185 90)
		(property "Reference" "R1023"
			(at -7.980172 -2.986786 0)
			(unlocked yes)
			(layer "F.SilkS")
			(effects
				(font
					(size 0.7874 0.5842)
					(thickness 0.1524)
				)
				(justify left)
			)
		)
		(property "Value" ""
			(at 0 0 90)
			(layer "F.Fab")
			(effects
				(font
					(size 1.27 1.27)
				)
			)
		)
		(duplicate_pad_numbers_are_jumpers no)
		(fp_line
			(start 0.7874 -0.4064)
			(end 0.7874 0.4064)
			(stroke
				(width 0.1524)
				(type default)
			)
			(layer "F.SilkS")
		)
		(fp_line
			(start -0.7874 -0.4064)
			(end 0.7874 -0.4064)
			(stroke
				(width 0.1524)
				(type default)
			)
			(layer "F.SilkS")
		)
		(fp_line
			(start 0.7874 0.4064)
			(end -0.7874 0.4064)
			(stroke
				(width 0.1524)
				(type default)
			)
			(layer "F.SilkS")
		)
		(fp_line
			(start -0.7874 0.4064)
			(end -0.7874 -0.4064)
			(stroke
				(width 0.1524)
				(type default)
			)
			(layer "F.SilkS")
		)
		(fp_poly
			(pts
				(xy -0.508 0.2794) (xy -0.508 0.2286) (xy -0.635 0.2286) (xy -0.635 -0.254) (xy -0.5334 -0.254)
				(xy -0.5334 -0.2794) (xy 0.5334 -0.2794) (xy 0.5334 -0.254) (xy 0.635 -0.254) (xy 0.635 0.254) (xy 0.5334 0.254)
				(xy 0.5334 0.2794)
			)
			(stroke
				(width 0)
				(type default)
			)
			(fill no)
			(layer "F.CrtYd")
		)
		(pad "1" smd rect
			(at 0.40005 0 90)
			(size 0.4572 0.508)
			(layers "F.Cu" "F.Mask" "F.Paste")
			(net "SMB_BMC_NODE1_HSC_ALERT_L")
		)
		(pad "2" smd rect
			(at -0.40005 0 90)
			(size 0.4572 0.508)
			(layers "F.Cu" "F.Mask" "F.Paste")
			(net "P3V3_SUS_NODE1")
		)
	)
	(footprint ""
		(layer "F.Cu")
		(at 120.85193 -70.425818)
		(property "Reference" "U3"
			(at -1.069594 -2.505202 0)
			(unlocked yes)
			(layer "F.SilkS")
			(effects
				(font
					(size 0.7874 0.5842)
					(thickness 0.1524)
				)
			)
		)
		(property "Value" ""
			(at 0 0 0)
			(layer "F.Fab")
			(effects
				(font
					(size 1.27 1.27)
				)
			)
		)
		(duplicate_pad_numbers_are_jumpers no)
		(fp_line
			(start -1.651 -1.905)
			(end 1.651 -1.905)
			(stroke
				(width 0.1524)
				(type default)
			)
			(layer "F.SilkS")
		)
		(fp_line
			(start -1.651 1.905)
			(end -1.651 -1.905)
			(stroke
				(width 0.1524)
				(type default)
			)
			(layer "F.SilkS")
		)
		(fp_line
			(start 1.651 -1.905)
			(end 1.651 1.905)
			(stroke
				(width 0.1524)
				(type default)
			)
			(layer "F.SilkS")
		)
		(fp_line
			(start 1.651 1.905)
			(end -1.651 1.905)
			(stroke
				(width 0.1524)
				(type default)
			)
			(layer "F.SilkS")
		)
		(fp_poly
			(pts
				(xy -1.524 0.7112) (xy -1.524 1.7526) (xy -0.508 1.7526) (xy -0.508 0.6985) (xy 0.508 0.6985) (xy 0.508 1.7526)
				(xy 1.524 1.7526) (xy 1.524 0.6985) (xy 1.524 -0.6985) (xy 0.508 -0.6985) (xy 0.508 -1.7526) (xy -0.508 -1.7526)
				(xy -0.508 -0.6985) (xy -1.524 -0.6985) (xy -1.524 0.6985)
			)
			(stroke
				(width 0)
				(type default)
			)
			(fill no)
			(layer "F.CrtYd")
		)
		(fp_text user "1"
			(at -2.094484 0.8509 0)
			(unlocked yes)
			(layer "F.SilkS")
			(effects
				(font
					(size 0.635 0.4064)
					(thickness 0.1524)
				)
			)
		)
		(fp_text user "3"
			(at 1.08204 -2.361946 0)
			(unlocked yes)
			(layer "F.SilkS")
			(effects
				(font
					(size 0.635 0.4064)
					(thickness 0.1524)
				)
			)
		)
		(fp_text user "2"
			(at 2.131822 2.203704 0)
			(unlocked yes)
			(layer "F.SilkS")
			(effects
				(font
					(size 0.635 0.4064)
					(thickness 0.1524)
				)
			)
		)
		(pad "1" smd rect
			(at -1.016 1.1176)
			(size 1.016 1.27)
			(layers "F.Cu" "F.Mask" "F.Paste")
			(net "P3V3_STB_NODE1")
		)
		(pad "2" smd rect
			(at 1.016 1.1176)
			(size 1.016 1.27)
			(layers "F.Cu" "F.Mask" "F.Paste")
			(net "P3V0_BAT_NODE1_R")
		)
		(pad "3" smd rect
			(at 0 -1.1176)
			(size 1.016 1.27)
			(layers "F.Cu" "F.Mask" "F.Paste")
			(net "P3V3_RTC_NODE1")
		)
	)
	(footprint ""
		(layer "F.Cu")
		(at 23.84171 -110.729522 180)
		(property "Reference" "PC68"
			(at -2.97815 2.097532 0)
			(unlocked yes)
			(layer "F.SilkS")
			(effects
				(font
					(size 0.7874 0.5842)
					(thickness 0.1524)
				)
				(justify left)
			)
		)
		(property "Value" ""
			(at 0 0 180)
			(layer "F.Fab")
			(effects
				(font
					(size 1.27 1.27)
				)
			)
		)
		(duplicate_pad_numbers_are_jumpers no)
		(fp_line
			(start 1.905 0.8636)
			(end -1.905 0.8636)
			(stroke
				(width 0.1524)
				(type default)
			)
			(layer "F.SilkS")
		)
		(fp_line
			(start 1.905 -0.8636)
			(end 1.905 0.8636)
			(stroke
				(width 0.1524)
				(type default)
			)
			(layer "F.SilkS")
		)
		(fp_line
			(start 0 0.837946)
			(end 0 -0.837946)
			(stroke
				(width 0.1524)
				(type default)
			)
			(layer "F.SilkS")
		)
		(fp_line
			(start -1.905 0.8636)
			(end -1.905 -0.8636)
			(stroke
				(width 0.1524)
				(type default)
			)
			(layer "F.SilkS")
		)
		(fp_line
			(start -1.905 -0.8636)
			(end 1.905 -0.8636)
			(stroke
				(width 0.1524)
				(type default)
			)
			(layer "F.SilkS")
		)
		(fp_rect
			(start -1.524 0.7366)
			(end 1.524 -0.7366)
			(stroke
				(width 0)
				(type default)
			)
			(fill no)
			(layer "F.CrtYd")
		)
		(pad "1" smd rect
			(at 0.94996 0 180)
			(size 1.1176 1.3716)
			(layers "F.Cu" "F.Mask" "F.Paste")
			(net "P1V05_NODE1")
		)
		(pad "2" smd rect
			(at -0.94996 0 180)
			(size 1.1176 1.3716)
			(layers "F.Cu" "F.Mask" "F.Paste")
			(net "GND")
		)
	)
	(footprint ""
		(layer "F.Cu")
		(at 8.19658 -154.13736 -90)
		(property "Reference" "R1299"
			(at 5.109464 -8.876792 90)
			(unlocked yes)
			(layer "F.SilkS")
			(effects
				(font
					(size 0.7874 0.5842)
					(thickness 0.1524)
				)
				(justify left)
			)
		)
		(property "Value" ""
			(at 0 0 270)
			(layer "F.Fab")
			(effects
				(font
					(size 1.27 1.27)
				)
			)
		)
		(duplicate_pad_numbers_are_jumpers no)
		(fp_line
			(start -0.7874 0.4064)
			(end -0.7874 -0.4064)
			(stroke
				(width 0.1524)
				(type default)
			)
			(layer "F.SilkS")
		)
		(fp_line
			(start 0.7874 0.4064)
			(end -0.7874 0.4064)
			(stroke
				(width 0.1524)
				(type default)
			)
			(layer "F.SilkS")
		)
		(fp_line
			(start -0.7874 -0.4064)
			(end 0.7874 -0.4064)
			(stroke
				(width 0.1524)
				(type default)
			)
			(layer "F.SilkS")
		)
		(fp_line
			(start 0.7874 -0.4064)
			(end 0.7874 0.4064)
			(stroke
				(width 0.1524)
				(type default)
			)
			(layer "F.SilkS")
		)
		(fp_poly
			(pts
				(xy -0.508 0.2794) (xy -0.508 0.2286) (xy -0.635 0.2286) (xy -0.635 -0.254) (xy -0.5334 -0.254)
				(xy -0.5334 -0.2794) (xy 0.5334 -0.2794) (xy 0.5334 -0.254) (xy 0.635 -0.254) (xy 0.635 0.254) (xy 0.5334 0.254)
				(xy 0.5334 0.2794)
			)
			(stroke
				(width 0)
				(type default)
			)
			(fill no)
			(layer "F.CrtYd")
		)
		(pad "1" smd rect
			(at 0.40005 0 270)
			(size 0.4572 0.508)
			(layers "F.Cu" "F.Mask" "F.Paste")
			(net "P3V3_NODE1")
		)
		(pad "2" smd rect
			(at -0.40005 0 270)
			(size 0.4572 0.508)
			(layers "F.Cu" "F.Mask" "F.Paste")
			(net "N54258474")
		)
	)
	(footprint ""
		(layer "F.Cu")
		(at 31.122112 -169.072052)
		(property "Reference" "R1251"
			(at -3.05562 6.778752 0)
			(unlocked yes)
			(layer "F.SilkS")
			(effects
				(font
					(size 0.7874 0.5842)
					(thickness 0.1524)
				)
				(justify left)
			)
		)
		(property "Value" ""
			(at 0 0 0)
			(layer "F.Fab")
			(effects
				(font
					(size 1.27 1.27)
				)
			)
		)
		(duplicate_pad_numbers_are_jumpers no)
		(fp_line
			(start -0.7874 -0.4064)
			(end 0.7874 -0.4064)
			(stroke
				(width 0.1524)
				(type default)
			)
			(layer "F.SilkS")
		)
		(fp_line
			(start -0.7874 0.4064)
			(end -0.7874 -0.4064)
			(stroke
				(width 0.1524)
				(type default)
			)
			(layer "F.SilkS")
		)
		(fp_line
			(start 0.7874 -0.4064)
			(end 0.7874 0.4064)
			(stroke
				(width 0.1524)
				(type default)
			)
			(layer "F.SilkS")
		)
		(fp_line
			(start 0.7874 0.4064)
			(end -0.7874 0.4064)
			(stroke
				(width 0.1524)
				(type default)
			)
			(layer "F.SilkS")
		)
		(fp_poly
			(pts
				(xy -0.508 0.2794) (xy -0.508 0.2286) (xy -0.635 0.2286) (xy -0.635 -0.254) (xy -0.5334 -0.254)
				(xy -0.5334 -0.2794) (xy 0.5334 -0.2794) (xy 0.5334 -0.254) (xy 0.635 -0.254) (xy 0.635 0.254) (xy 0.5334 0.254)
				(xy 0.5334 0.2794)
			)
			(stroke
				(width 0)
				(type default)
			)
			(fill no)
			(layer "F.CrtYd")
		)
		(pad "1" smd rect
			(at 0.40005 0)
			(size 0.4572 0.508)
			(layers "F.Cu" "F.Mask" "F.Paste")
			(net "CM_PWR_CTL_IN_R")
		)
		(pad "2" smd rect
			(at -0.40005 0)
			(size 0.4572 0.508)
			(layers "F.Cu" "F.Mask" "F.Paste")
			(net "GND")
		)
	)
	(footprint ""
		(layer "F.Cu")
		(at 71.10476 -188.126624 -90)
		(property "Reference" "R950"
			(at -4.548886 0.908558 90)
			(unlocked yes)
			(layer "F.SilkS")
			(effects
				(font
					(size 0.7874 0.5842)
					(thickness 0.1524)
				)
				(justify left)
			)
		)
		(property "Value" ""
			(at 0 0 270)
			(layer "F.Fab")
			(effects
				(font
					(size 1.27 1.27)
				)
			)
		)
		(duplicate_pad_numbers_are_jumpers no)
		(fp_line
			(start -0.7874 0.4064)
			(end -0.7874 -0.4064)
			(stroke
				(width 0.1524)
				(type default)
			)
			(layer "F.SilkS")
		)
		(fp_line
			(start 0.7874 0.4064)
			(end -0.7874 0.4064)
			(stroke
				(width 0.1524)
				(type default)
			)
			(layer "F.SilkS")
		)
		(fp_line
			(start -0.7874 -0.4064)
			(end 0.7874 -0.4064)
			(stroke
				(width 0.1524)
				(type default)
			)
			(layer "F.SilkS")
		)
		(fp_line
			(start 0.7874 -0.4064)
			(end 0.7874 0.4064)
			(stroke
				(width 0.1524)
				(type default)
			)
			(layer "F.SilkS")
		)
		(fp_poly
			(pts
				(xy -0.508 0.2794) (xy -0.508 0.2286) (xy -0.635 0.2286) (xy -0.635 -0.254) (xy -0.5334 -0.254)
				(xy -0.5334 -0.2794) (xy 0.5334 -0.2794) (xy 0.5334 -0.254) (xy 0.635 -0.254) (xy 0.635 0.254) (xy 0.5334 0.254)
				(xy 0.5334 0.2794)
			)
			(stroke
				(width 0)
				(type default)
			)
			(fill no)
			(layer "F.CrtYd")
		)
		(pad "1" smd rect
			(at 0.40005 0 270)
			(size 0.4572 0.508)
			(layers "F.Cu" "F.Mask" "F.Paste")
			(net "UART_T4_NODE4_RXD")
		)
		(pad "2" smd rect
			(at -0.40005 0 270)
			(size 0.4572 0.508)
			(layers "F.Cu" "F.Mask" "F.Paste")
			(net "UART_T4_NODE4_RXD_R")
		)
	)
	(footprint ""
		(layer "F.Cu")
		(at 155.685998 -142.93723 -90)
		(property "Reference" "R568"
			(at -1.23063 -0.43307 90)
			(unlocked yes)
			(layer "F.SilkS")
			(effects
				(font
					(size 0.7874 0.5842)
					(thickness 0.1524)
				)
				(justify left)
			)
		)
		(property "Value" ""
			(at 0 0 270)
			(layer "F.Fab")
			(effects
				(font
					(size 1.27 1.27)
				)
			)
		)
		(duplicate_pad_numbers_are_jumpers no)
		(fp_line
			(start -0.7874 0.4064)
			(end -0.7874 -0.4064)
			(stroke
				(width 0.1524)
				(type default)
			)
			(layer "F.SilkS")
		)
		(fp_line
			(start 0.7874 0.4064)
			(end -0.7874 0.4064)
			(stroke
				(width 0.1524)
				(type default)
			)
			(layer "F.SilkS")
		)
		(fp_line
			(start -0.7874 -0.4064)
			(end 0.7874 -0.4064)
			(stroke
				(width 0.1524)
				(type default)
			)
			(layer "F.SilkS")
		)
		(fp_line
			(start 0.7874 -0.4064)
			(end 0.7874 0.4064)
			(stroke
				(width 0.1524)
				(type default)
			)
			(layer "F.SilkS")
		)
		(fp_poly
			(pts
				(xy -0.508 0.2794) (xy -0.508 0.2286) (xy -0.635 0.2286) (xy -0.635 -0.254) (xy -0.5334 -0.254)
				(xy -0.5334 -0.2794) (xy 0.5334 -0.2794) (xy 0.5334 -0.254) (xy 0.635 -0.254) (xy 0.635 0.254) (xy 0.5334 0.254)
				(xy 0.5334 0.2794)
			)
			(stroke
				(width 0)
				(type default)
			)
			(fill no)
			(layer "F.CrtYd")
		)
		(pad "1" smd rect
			(at 0.40005 0 270)
			(size 0.4572 0.508)
			(layers "F.Cu" "F.Mask" "F.Paste")
			(net "P3V3_NODE1")
		)
		(pad "2" smd rect
			(at -0.40005 0 270)
			(size 0.4572 0.508)
			(layers "F.Cu" "F.Mask" "F.Paste")
			(net "PU_LAN2_TMS")
		)
	)
	(footprint ""
		(layer "F.Cu")
		(at 76.490068 -94.131892 -90)
		(property "Reference" "R157"
			(at 55.53329 -24.083264 90)
			(unlocked yes)
			(layer "F.SilkS")
			(effects
				(font
					(size 0.7874 0.5842)
					(thickness 0.1524)
				)
				(justify left)
			)
		)
		(property "Value" ""
			(at 0 0 270)
			(layer "F.Fab")
			(effects
				(font
					(size 1.27 1.27)
				)
			)
		)
		(duplicate_pad_numbers_are_jumpers no)
		(fp_line
			(start -0.7874 0.4064)
			(end -0.7874 -0.4064)
			(stroke
				(width 0.1524)
				(type default)
			)
			(layer "F.SilkS")
		)
		(fp_line
			(start 0.7874 0.4064)
			(end -0.7874 0.4064)
			(stroke
				(width 0.1524)
				(type default)
			)
			(layer "F.SilkS")
		)
		(fp_line
			(start -0.7874 -0.4064)
			(end 0.7874 -0.4064)
			(stroke
				(width 0.1524)
				(type default)
			)
			(layer "F.SilkS")
		)
		(fp_line
			(start 0.7874 -0.4064)
			(end 0.7874 0.4064)
			(stroke
				(width 0.1524)
				(type default)
			)
			(layer "F.SilkS")
		)
		(fp_poly
			(pts
				(xy -0.508 0.2794) (xy -0.508 0.2286) (xy -0.635 0.2286) (xy -0.635 -0.254) (xy -0.5334 -0.254)
				(xy -0.5334 -0.2794) (xy 0.5334 -0.2794) (xy 0.5334 -0.254) (xy 0.635 -0.254) (xy 0.635 0.254) (xy 0.5334 0.254)
				(xy 0.5334 0.2794)
			)
			(stroke
				(width 0)
				(type default)
			)
			(fill no)
			(layer "F.CrtYd")
		)
		(pad "1" smd rect
			(at 0.40005 0 270)
			(size 0.4572 0.508)
			(layers "F.Cu" "F.Mask" "F.Paste")
			(net "PD_CPU_NODE1_NODE_ID")
		)
		(pad "2" smd rect
			(at -0.40005 0 270)
			(size 0.4572 0.508)
			(layers "F.Cu" "F.Mask" "F.Paste")
			(net "P3V3_NODE1")
		)
	)
)
